(kicad_pcb
	(version 20260206)
	(generator "pcbnew")
	(generator_version "10.0")
	(general
		(thickness 1.6)
		(legacy_teardrops no)
	)
	(paper "A4")
	(title_block
		(title "03242023_DA0F0TMBIJ0_F0T_Motherboard_J_brd_V01_OCP.brd")
		(comment 1 "Grand Teton / footprints 1491-1496 of 6105")
	)
	(layers
		(0 "F.Cu" signal "TOP")
		(4 "In1.Cu" signal "GND")
		(6 "In2.Cu" signal "IN1")
		(8 "In3.Cu" signal "GND1")
		(10 "In4.Cu" signal "IN2")
		(12 "In5.Cu" signal "GND2")
		(14 "In6.Cu" signal "IN3")
		(16 "In7.Cu" signal "GND3")
		(18 "In8.Cu" signal "VCC")
		(20 "In9.Cu" signal "VCC1")
		(22 "In10.Cu" signal "GND4")
		(24 "In11.Cu" signal "IN4")
		(26 "In12.Cu" signal "GND5")
		(28 "In13.Cu" signal "IN5")
		(30 "In14.Cu" signal "GND6")
		(32 "In15.Cu" signal "IN6")
		(34 "In16.Cu" signal "GND7")
		(2 "B.Cu" signal "BOTTOM")
		(9 "F.Adhes" user "F.Adhesive")
		(11 "B.Adhes" user "B.Adhesive")
		(13 "F.Paste" user "Package Geometry/Pastemask Top")
		(15 "B.Paste" user "Package Geometry/Pastemask Bottom")
		(5 "F.SilkS" user "Ref Des/Silkscreen Top")
		(7 "B.SilkS" user "Ref Des/Silkscreen Bottom")
		(1 "F.Mask" user "Board Geometry/Soldermask Top")
		(3 "B.Mask" user "Board Geometry/Soldermask Bottom")
		(17 "Dwgs.User" user "User.Drawings")
		(19 "Cmts.User" user "User.Comments")
		(21 "Eco1.User" user "User.Eco1")
		(23 "Eco2.User" user "User.Eco2")
		(25 "Edge.Cuts" user "Board Geometry/Outline")
		(27 "Margin" user)
		(31 "F.CrtYd" user "Package Geometry/Place Bound Top")
		(29 "B.CrtYd" user "Package Geometry/Place Bound Bottom")
		(35 "F.Fab" user "Ref Des/Assembly Top")
		(33 "B.Fab" user "Ref Des/Assembly Bottom")
	)
	(footprint ""
		(layer "F.Cu")
		(at 240.219738 -119.183658 -90)
		(property "Reference" "R3199"
			(at 0 0 270)
			(layer "F.SilkS")
			(hide yes)
			(effects
				(font
					(size 1.27 1.27)
				)
			)
		)
		(property "Value" ""
			(at 0 0 270)
			(layer "F.Fab")
			(effects
				(font
					(size 1.27 1.27)
				)
			)
		)
		(duplicate_pad_numbers_are_jumpers no)
		(fp_line
			(start 0.385318 0.4064)
			(end -0.254762 0.4064)
			(stroke
				(width 0.1524)
				(type default)
			)
			(layer "F.SilkS")
		)
		(fp_line
			(start -0.7874 0.044958)
			(end -0.7874 -0.4064)
			(stroke
				(width 0.1524)
				(type default)
			)
			(layer "F.SilkS")
		)
		(fp_line
			(start -0.7874 -0.4064)
			(end 0.7874 -0.4064)
			(stroke
				(width 0.1524)
				(type default)
			)
			(layer "F.SilkS")
		)
		(fp_line
			(start 0.7874 -0.4064)
			(end 0.7874 0.093218)
			(stroke
				(width 0.1524)
				(type default)
			)
			(layer "F.SilkS")
		)
		(fp_line
			(start -0.67945 0.3048)
			(end -0.67945 -0.305054)
			(stroke
				(width 0.1)
				(type default)
			)
			(layer "F.Fab")
		)
		(fp_line
			(start -0.12065 0.3048)
			(end -0.67945 0.3048)
			(stroke
				(width 0.1)
				(type default)
			)
			(layer "F.Fab")
		)
		(fp_line
			(start 0.120396 0.3048)
			(end 0.120396 0.2794)
			(stroke
				(width 0.1)
				(type default)
			)
			(layer "F.Fab")
		)
		(fp_line
			(start 0.67945 0.3048)
			(end 0.120396 0.3048)
			(stroke
				(width 0.1)
				(type default)
			)
			(layer "F.Fab")
		)
		(fp_line
			(start -0.12065 0.2794)
			(end -0.12065 0.3048)
			(stroke
				(width 0.1)
				(type default)
			)
			(layer "F.Fab")
		)
		(fp_line
			(start 0.120396 0.2794)
			(end -0.12065 0.2794)
			(stroke
				(width 0.1)
				(type default)
			)
			(layer "F.Fab")
		)
		(fp_line
			(start -0.12065 -0.2794)
			(end 0.12065 -0.2794)
			(stroke
				(width 0.1)
				(type default)
			)
			(layer "F.Fab")
		)
		(fp_line
			(start 0.12065 -0.2794)
			(end 0.12065 -0.3048)
			(stroke
				(width 0.1)
				(type default)
			)
			(layer "F.Fab")
		)
		(fp_line
			(start 0.12065 -0.3048)
			(end 0.67945 -0.3048)
			(stroke
				(width 0.1)
				(type default)
			)
			(layer "F.Fab")
		)
		(fp_line
			(start 0.67945 -0.3048)
			(end 0.67945 0.3048)
			(stroke
				(width 0.1)
				(type default)
			)
			(layer "F.Fab")
		)
		(fp_line
			(start -0.67945 -0.305054)
			(end -0.12065 -0.305054)
			(stroke
				(width 0.1)
				(type default)
			)
			(layer "F.Fab")
		)
		(fp_line
			(start -0.12065 -0.305054)
			(end -0.12065 -0.2794)
			(stroke
				(width 0.1)
				(type default)
			)
			(layer "F.Fab")
		)
		(pad "1" smd circle
			(at -0.40005 0 270)
			(size 0 0)
			(layers "F.Cu" "F.Mask" "F.Paste")
			(net "CLK_100M_OCP_V3_2_C_R_DN")
		)
		(pad "2" smd circle
			(at 0.40005 0 270)
			(size 0 0)
			(layers "F.Cu" "F.Mask" "F.Paste")
			(net "CLK_100M_OCP_V3_2_C_DN")
		)
	)
	(footprint ""
		(layer "F.Cu")
		(at 164.64788 -104.485948 180)
		(property "Reference" "R2662"
			(at 0 0 180)
			(layer "F.SilkS")
			(hide yes)
			(effects
				(font
					(size 1.27 1.27)
				)
			)
		)
		(property "Value" ""
			(at 0 0 180)
			(layer "F.Fab")
			(effects
				(font
					(size 1.27 1.27)
				)
			)
		)
		(duplicate_pad_numbers_are_jumpers no)
		(fp_line
			(start 0.7874 0.4064)
			(end -0.7874 0.4064)
			(stroke
				(width 0.1524)
				(type default)
			)
			(layer "F.SilkS")
		)
		(fp_line
			(start 0.7874 -0.4064)
			(end 0.7874 0.4064)
			(stroke
				(width 0.1524)
				(type default)
			)
			(layer "F.SilkS")
		)
		(fp_line
			(start -0.7874 0.4064)
			(end -0.7874 -0.4064)
			(stroke
				(width 0.1524)
				(type default)
			)
			(layer "F.SilkS")
		)
		(fp_line
			(start -0.7874 -0.4064)
			(end 0.7874 -0.4064)
			(stroke
				(width 0.1524)
				(type default)
			)
			(layer "F.SilkS")
		)
		(fp_line
			(start 0.67945 0.3048)
			(end 0.120396 0.3048)
			(stroke
				(width 0.1)
				(type default)
			)
			(layer "F.Fab")
		)
		(fp_line
			(start 0.67945 -0.3048)
			(end 0.67945 0.3048)
			(stroke
				(width 0.1)
				(type default)
			)
			(layer "F.Fab")
		)
		(fp_line
			(start 0.12065 -0.2794)
			(end 0.12065 -0.3048)
			(stroke
				(width 0.1)
				(type default)
			)
			(layer "F.Fab")
		)
		(fp_line
			(start 0.12065 -0.3048)
			(end 0.67945 -0.3048)
			(stroke
				(width 0.1)
				(type default)
			)
			(layer "F.Fab")
		)
		(fp_line
			(start 0.120396 0.3048)
			(end 0.120396 0.2794)
			(stroke
				(width 0.1)
				(type default)
			)
			(layer "F.Fab")
		)
		(fp_line
			(start 0.120396 0.2794)
			(end -0.12065 0.2794)
			(stroke
				(width 0.1)
				(type default)
			)
			(layer "F.Fab")
		)
		(fp_line
			(start -0.12065 0.3048)
			(end -0.67945 0.3048)
			(stroke
				(width 0.1)
				(type default)
			)
			(layer "F.Fab")
		)
		(fp_line
			(start -0.12065 0.2794)
			(end -0.12065 0.3048)
			(stroke
				(width 0.1)
				(type default)
			)
			(layer "F.Fab")
		)
		(fp_line
			(start -0.12065 -0.2794)
			(end 0.12065 -0.2794)
			(stroke
				(width 0.1)
				(type default)
			)
			(layer "F.Fab")
		)
		(fp_line
			(start -0.12065 -0.305054)
			(end -0.12065 -0.2794)
			(stroke
				(width 0.1)
				(type default)
			)
			(layer "F.Fab")
		)
		(fp_line
			(start -0.67945 0.3048)
			(end -0.67945 -0.305054)
			(stroke
				(width 0.1)
				(type default)
			)
			(layer "F.Fab")
		)
		(fp_line
			(start -0.67945 -0.305054)
			(end -0.12065 -0.305054)
			(stroke
				(width 0.1)
				(type default)
			)
			(layer "F.Fab")
		)
		(pad "1" smd circle
			(at -0.40005 0 180)
			(size 0 0)
			(layers "F.Cu" "F.Mask" "F.Paste")
			(net "FM_GPU_PWR_EN")
		)
		(pad "2" smd circle
			(at 0.40005 0 180)
			(size 0 0)
			(layers "F.Cu" "F.Mask" "F.Paste")
			(net "FM_GPU_PWR_EN_R")
		)
	)
	(footprint ""
		(layer "F.Cu")
		(at 21.73351 -168.183306 90)
		(property "Reference" "R223"
			(at 0 0 90)
			(layer "F.SilkS")
			(hide yes)
			(effects
				(font
					(size 1.27 1.27)
				)
			)
		)
		(property "Value" ""
			(at 0 0 90)
			(layer "F.Fab")
			(effects
				(font
					(size 1.27 1.27)
				)
			)
		)
		(duplicate_pad_numbers_are_jumpers no)
		(fp_line
			(start 0.7874 -0.4064)
			(end 0.7874 0.4064)
			(stroke
				(width 0.1524)
				(type default)
			)
			(layer "F.SilkS")
		)
		(fp_line
			(start -0.7874 -0.4064)
			(end 0.7874 -0.4064)
			(stroke
				(width 0.1524)
				(type default)
			)
			(layer "F.SilkS")
		)
		(fp_line
			(start 0.7874 0.4064)
			(end -0.7874 0.4064)
			(stroke
				(width 0.1524)
				(type default)
			)
			(layer "F.SilkS")
		)
		(fp_line
			(start -0.7874 0.4064)
			(end -0.7874 -0.4064)
			(stroke
				(width 0.1524)
				(type default)
			)
			(layer "F.SilkS")
		)
		(fp_line
			(start -0.12065 -0.305054)
			(end -0.12065 -0.2794)
			(stroke
				(width 0.1)
				(type default)
			)
			(layer "F.Fab")
		)
		(fp_line
			(start -0.67945 -0.305054)
			(end -0.12065 -0.305054)
			(stroke
				(width 0.1)
				(type default)
			)
			(layer "F.Fab")
		)
		(fp_line
			(start 0.67945 -0.3048)
			(end 0.67945 0.3048)
			(stroke
				(width 0.1)
				(type default)
			)
			(layer "F.Fab")
		)
		(fp_line
			(start 0.12065 -0.3048)
			(end 0.67945 -0.3048)
			(stroke
				(width 0.1)
				(type default)
			)
			(layer "F.Fab")
		)
		(fp_line
			(start 0.12065 -0.2794)
			(end 0.12065 -0.3048)
			(stroke
				(width 0.1)
				(type default)
			)
			(layer "F.Fab")
		)
		(fp_line
			(start -0.12065 -0.2794)
			(end 0.12065 -0.2794)
			(stroke
				(width 0.1)
				(type default)
			)
			(layer "F.Fab")
		)
		(fp_line
			(start 0.120396 0.2794)
			(end -0.12065 0.2794)
			(stroke
				(width 0.1)
				(type default)
			)
			(layer "F.Fab")
		)
		(fp_line
			(start -0.12065 0.2794)
			(end -0.12065 0.3048)
			(stroke
				(width 0.1)
				(type default)
			)
			(layer "F.Fab")
		)
		(fp_line
			(start 0.67945 0.3048)
			(end 0.120396 0.3048)
			(stroke
				(width 0.1)
				(type default)
			)
			(layer "F.Fab")
		)
		(fp_line
			(start 0.120396 0.3048)
			(end 0.120396 0.2794)
			(stroke
				(width 0.1)
				(type default)
			)
			(layer "F.Fab")
		)
		(fp_line
			(start -0.12065 0.3048)
			(end -0.67945 0.3048)
			(stroke
				(width 0.1)
				(type default)
			)
			(layer "F.Fab")
		)
		(fp_line
			(start -0.67945 0.3048)
			(end -0.67945 -0.305054)
			(stroke
				(width 0.1)
				(type default)
			)
			(layer "F.Fab")
		)
		(pad "1" smd circle
			(at -0.40005 0 90)
			(size 0 0)
			(layers "F.Cu" "F.Mask" "F.Paste")
			(net "P3V3_AUX")
		)
		(pad "2" smd circle
			(at 0.40005 0 90)
			(size 0 0)
			(layers "F.Cu" "F.Mask" "F.Paste")
			(net "IRQ_PVCCD_CPU1_VRHOT_LVC3_N")
		)
	)
	(footprint ""
		(layer "F.Cu")
		(at 437.425846 -380.05258 180)
		(property "Reference" "PC1852"
			(at 0 0 180)
			(layer "F.SilkS")
			(hide yes)
			(effects
				(font
					(size 1.27 1.27)
				)
			)
		)
		(property "Value" ""
			(at 0 0 180)
			(layer "F.Fab")
			(effects
				(font
					(size 1.27 1.27)
				)
			)
		)
		(duplicate_pad_numbers_are_jumpers no)
		(fp_line
			(start 0.7874 0.4064)
			(end -0.7874 0.4064)
			(stroke
				(width 0.1524)
				(type default)
			)
			(layer "F.SilkS")
		)
		(fp_line
			(start 0.7874 -0.4064)
			(end 0.7874 0.4064)
			(stroke
				(width 0.1524)
				(type default)
			)
			(layer "F.SilkS")
		)
		(fp_line
			(start -0.7874 0.4064)
			(end -0.7874 -0.4064)
			(stroke
				(width 0.1524)
				(type default)
			)
			(layer "F.SilkS")
		)
		(fp_line
			(start -0.7874 -0.4064)
			(end 0.7874 -0.4064)
			(stroke
				(width 0.1524)
				(type default)
			)
			(layer "F.SilkS")
		)
		(fp_line
			(start 0.67945 0.3048)
			(end 0.120396 0.3048)
			(stroke
				(width 0.1)
				(type default)
			)
			(layer "F.Fab")
		)
		(fp_line
			(start 0.67945 -0.3048)
			(end 0.67945 0.3048)
			(stroke
				(width 0.1)
				(type default)
			)
			(layer "F.Fab")
		)
		(fp_line
			(start 0.12065 -0.2794)
			(end 0.12065 -0.3048)
			(stroke
				(width 0.1)
				(type default)
			)
			(layer "F.Fab")
		)
		(fp_line
			(start 0.12065 -0.3048)
			(end 0.67945 -0.3048)
			(stroke
				(width 0.1)
				(type default)
			)
			(layer "F.Fab")
		)
		(fp_line
			(start 0.120396 0.3048)
			(end 0.120396 0.2794)
			(stroke
				(width 0.1)
				(type default)
			)
			(layer "F.Fab")
		)
		(fp_line
			(start 0.120396 0.2794)
			(end -0.12065 0.2794)
			(stroke
				(width 0.1)
				(type default)
			)
			(layer "F.Fab")
		)
		(fp_line
			(start -0.12065 0.3048)
			(end -0.67945 0.3048)
			(stroke
				(width 0.1)
				(type default)
			)
			(layer "F.Fab")
		)
		(fp_line
			(start -0.12065 0.2794)
			(end -0.12065 0.3048)
			(stroke
				(width 0.1)
				(type default)
			)
			(layer "F.Fab")
		)
		(fp_line
			(start -0.12065 -0.2794)
			(end 0.12065 -0.2794)
			(stroke
				(width 0.1)
				(type default)
			)
			(layer "F.Fab")
		)
		(fp_line
			(start -0.12065 -0.305054)
			(end -0.12065 -0.2794)
			(stroke
				(width 0.1)
				(type default)
			)
			(layer "F.Fab")
		)
		(fp_line
			(start -0.67945 0.3048)
			(end -0.67945 -0.305054)
			(stroke
				(width 0.1)
				(type default)
			)
			(layer "F.Fab")
		)
		(fp_line
			(start -0.67945 -0.305054)
			(end -0.12065 -0.305054)
			(stroke
				(width 0.1)
				(type default)
			)
			(layer "F.Fab")
		)
		(pad "1" smd circle
			(at -0.40005 0 180)
			(size 0 0)
			(layers "F.Cu" "F.Mask" "F.Paste")
			(net "P5V_AUX")
		)
		(pad "2" smd circle
			(at 0.40005 0 180)
			(size 0 0)
			(layers "F.Cu" "F.Mask" "F.Paste")
			(net "GND")
		)
	)
	(footprint ""
		(layer "F.Cu")
		(at 436.10911 -19.611086 -90)
		(property "Reference" "R417"
			(at 0 0 270)
			(layer "F.SilkS")
			(hide yes)
			(effects
				(font
					(size 1.27 1.27)
				)
			)
		)
		(property "Value" ""
			(at 0 0 270)
			(layer "F.Fab")
			(effects
				(font
					(size 1.27 1.27)
				)
			)
		)
		(duplicate_pad_numbers_are_jumpers no)
		(fp_line
			(start -0.7874 0.4064)
			(end -0.7874 -0.4064)
			(stroke
				(width 0.1524)
				(type default)
			)
			(layer "F.SilkS")
		)
		(fp_line
			(start 0.7874 0.4064)
			(end -0.7874 0.4064)
			(stroke
				(width 0.1524)
				(type default)
			)
			(layer "F.SilkS")
		)
		(fp_line
			(start -0.7874 -0.4064)
			(end 0.7874 -0.4064)
			(stroke
				(width 0.1524)
				(type default)
			)
			(layer "F.SilkS")
		)
		(fp_line
			(start 0.7874 -0.4064)
			(end 0.7874 0.4064)
			(stroke
				(width 0.1524)
				(type default)
			)
			(layer "F.SilkS")
		)
		(fp_line
			(start -0.67945 0.3048)
			(end -0.67945 -0.305054)
			(stroke
				(width 0.1)
				(type default)
			)
			(layer "F.Fab")
		)
		(fp_line
			(start -0.12065 0.3048)
			(end -0.67945 0.3048)
			(stroke
				(width 0.1)
				(type default)
			)
			(layer "F.Fab")
		)
		(fp_line
			(start 0.120396 0.3048)
			(end 0.120396 0.2794)
			(stroke
				(width 0.1)
				(type default)
			)
			(layer "F.Fab")
		)
		(fp_line
			(start 0.67945 0.3048)
			(end 0.120396 0.3048)
			(stroke
				(width 0.1)
				(type default)
			)
			(layer "F.Fab")
		)
		(fp_line
			(start -0.12065 0.2794)
			(end -0.12065 0.3048)
			(stroke
				(width 0.1)
				(type default)
			)
			(layer "F.Fab")
		)
		(fp_line
			(start 0.120396 0.2794)
			(end -0.12065 0.2794)
			(stroke
				(width 0.1)
				(type default)
			)
			(layer "F.Fab")
		)
		(fp_line
			(start -0.12065 -0.2794)
			(end 0.12065 -0.2794)
			(stroke
				(width 0.1)
				(type default)
			)
			(layer "F.Fab")
		)
		(fp_line
			(start 0.12065 -0.2794)
			(end 0.12065 -0.3048)
			(stroke
				(width 0.1)
				(type default)
			)
			(layer "F.Fab")
		)
		(fp_line
			(start 0.12065 -0.3048)
			(end 0.67945 -0.3048)
			(stroke
				(width 0.1)
				(type default)
			)
			(layer "F.Fab")
		)
		(fp_line
			(start 0.67945 -0.3048)
			(end 0.67945 0.3048)
			(stroke
				(width 0.1)
				(type default)
			)
			(layer "F.Fab")
		)
		(fp_line
			(start -0.67945 -0.305054)
			(end -0.12065 -0.305054)
			(stroke
				(width 0.1)
				(type default)
			)
			(layer "F.Fab")
		)
		(fp_line
			(start -0.12065 -0.305054)
			(end -0.12065 -0.2794)
			(stroke
				(width 0.1)
				(type default)
			)
			(layer "F.Fab")
		)
		(pad "1" smd circle
			(at -0.40005 0 270)
			(size 0 0)
			(layers "F.Cu" "F.Mask" "F.Paste")
			(net "OCP_SFF_ISO_BIF1_EN")
		)
		(pad "2" smd circle
			(at 0.40005 0 270)
			(size 0 0)
			(layers "F.Cu" "F.Mask" "F.Paste")
			(net "OCP_SFF_BIF1_R_N")
		)
	)
	(footprint ""
		(layer "F.Cu")
		(at 22.13356 -166.767256)
		(property "Reference" "PR215"
			(at 0 0 0)
			(layer "F.SilkS")
			(hide yes)
			(effects
				(font
					(size 1.27 1.27)
				)
			)
		)
		(property "Value" ""
			(at 0 0 0)
			(layer "F.Fab")
			(effects
				(font
					(size 1.27 1.27)
				)
			)
		)
		(duplicate_pad_numbers_are_jumpers no)
		(fp_line
			(start -0.7874 -0.4064)
			(end 0.7874 -0.4064)
			(stroke
				(width 0.1524)
				(type default)
			)
			(layer "F.SilkS")
		)
		(fp_line
			(start -0.7874 0.4064)
			(end -0.7874 -0.4064)
			(stroke
				(width 0.1524)
				(type default)
			)
			(layer "F.SilkS")
		)
		(fp_line
			(start 0.7874 -0.4064)
			(end 0.7874 0.4064)
			(stroke
				(width 0.1524)
				(type default)
			)
			(layer "F.SilkS")
		)
		(fp_line
			(start 0.7874 0.4064)
			(end -0.7874 0.4064)
			(stroke
				(width 0.1524)
				(type default)
			)
			(layer "F.SilkS")
		)
		(fp_line
			(start -0.67945 -0.305054)
			(end -0.12065 -0.305054)
			(stroke
				(width 0.1)
				(type default)
			)
			(layer "F.Fab")
		)
		(fp_line
			(start -0.67945 0.3048)
			(end -0.67945 -0.305054)
			(stroke
				(width 0.1)
				(type default)
			)
			(layer "F.Fab")
		)
		(fp_line
			(start -0.12065 -0.305054)
			(end -0.12065 -0.2794)
			(stroke
				(width 0.1)
				(type default)
			)
			(layer "F.Fab")
		)
		(fp_line
			(start -0.12065 -0.2794)
			(end 0.12065 -0.2794)
			(stroke
				(width 0.1)
				(type default)
			)
			(layer "F.Fab")
		)
		(fp_line
			(start -0.12065 0.2794)
			(end -0.12065 0.3048)
			(stroke
				(width 0.1)
				(type default)
			)
			(layer "F.Fab")
		)
		(fp_line
			(start -0.12065 0.3048)
			(end -0.67945 0.3048)
			(stroke
				(width 0.1)
				(type default)
			)
			(layer "F.Fab")
		)
		(fp_line
			(start 0.120396 0.2794)
			(end -0.12065 0.2794)
			(stroke
				(width 0.1)
				(type default)
			)
			(layer "F.Fab")
		)
		(fp_line
			(start 0.120396 0.3048)
			(end 0.120396 0.2794)
			(stroke
				(width 0.1)
				(type default)
			)
			(layer "F.Fab")
		)
		(fp_line
			(start 0.12065 -0.3048)
			(end 0.67945 -0.3048)
			(stroke
				(width 0.1)
				(type default)
			)
			(layer "F.Fab")
		)
		(fp_line
			(start 0.12065 -0.2794)
			(end 0.12065 -0.3048)
			(stroke
				(width 0.1)
				(type default)
			)
			(layer "F.Fab")
		)
		(fp_line
			(start 0.67945 -0.3048)
			(end 0.67945 0.3048)
			(stroke
				(width 0.1)
				(type default)
			)
			(layer "F.Fab")
		)
		(fp_line
			(start 0.67945 0.3048)
			(end 0.120396 0.3048)
			(stroke
				(width 0.1)
				(type default)
			)
			(layer "F.Fab")
		)
		(pad "1" smd circle
			(at -0.40005 0)
			(size 0 0)
			(layers "F.Cu" "F.Mask" "F.Paste")
			(net "P3V3_AUX")
		)
		(pad "2" smd circle
			(at 0.40005 0)
			(size 0 0)
			(layers "F.Cu" "F.Mask" "F.Paste")
			(net "PVCCD_HV_CPU1_PIN_ALT")
		)
	)
)
